(kicad_pcb
	(version 20260206)
	(generator "pcbnew")
	(generator_version "10.0")
	(general
		(thickness 1.6)
		(legacy_teardrops no)
	)
	(paper "A4")
	(title_block
		(title "01162023_DA0F0TEBIF0_F0T_Expander_BD_F_brd_V02_OCP.brd")
		(comment 1 "Grand Teton / footprints 8143-8150 of 9728")
	)
	(layers
		(0 "F.Cu" signal "TOP")
		(4 "In1.Cu" signal "GND")
		(6 "In2.Cu" signal "VCC")
		(8 "In3.Cu" signal "VCC1")
		(10 "In4.Cu" signal "GND1")
		(12 "In5.Cu" signal "IN1")
		(14 "In6.Cu" signal "GND2")
		(16 "In7.Cu" signal "IN2")
		(18 "In8.Cu" signal "GND3")
		(20 "In9.Cu" signal "IN3")
		(22 "In10.Cu" signal "GND4")
		(24 "In11.Cu" signal "IN4")
		(26 "In12.Cu" signal "GND5")
		(28 "In13.Cu" signal "IN5")
		(30 "In14.Cu" signal "GND6")
		(32 "In15.Cu" signal "IN6")
		(34 "In16.Cu" signal "GND7")
		(2 "B.Cu" signal "BOTTOM")
		(9 "F.Adhes" user "F.Adhesive")
		(11 "B.Adhes" user "B.Adhesive")
		(13 "F.Paste" user "Package Geometry/Pastemask Top")
		(15 "B.Paste" user "Package Geometry/Pastemask Bottom")
		(5 "F.SilkS" user "Ref Des/Silkscreen Top")
		(7 "B.SilkS" user "Ref Des/Silkscreen Bottom")
		(1 "F.Mask" user "Board Geometry/Soldermask Top")
		(3 "B.Mask" user "Board Geometry/Soldermask Bottom")
		(17 "Dwgs.User" user "User.Drawings")
		(19 "Cmts.User" user "User.Comments")
		(21 "Eco1.User" user "User.Eco1")
		(23 "Eco2.User" user "User.Eco2")
		(25 "Edge.Cuts" user "Board Geometry/Outline")
		(27 "Margin" user)
		(31 "F.CrtYd" user "Package Geometry/Place Bound Top")
		(29 "B.CrtYd" user "Package Geometry/Place Bound Bottom")
		(35 "F.Fab" user "Ref Des/Assembly Top")
		(33 "B.Fab" user "Ref Des/Assembly Bottom")
	)
	(footprint ""
		(layer "B.Cu")
		(at 133.78815 -321.844924 -90)
		(property "Reference" "R6480"
			(at 0 0 90)
			(layer "B.SilkS")
			(hide yes)
			(effects
				(font
					(size 1.27 1.27)
				)
				(justify mirror)
			)
		)
		(property "Value" ""
			(at 0 0 90)
			(layer "B.Fab")
			(effects
				(font
					(size 1.27 1.27)
				)
				(justify mirror)
			)
		)
		(duplicate_pad_numbers_are_jumpers no)
		(fp_line
			(start -0.7874 0.4064)
			(end 0.7874 0.4064)
			(stroke
				(width 0.1524)
				(type default)
			)
			(layer "B.SilkS")
		)
		(fp_line
			(start 0.7874 0.4064)
			(end 0.7874 -0.4064)
			(stroke
				(width 0.1524)
				(type default)
			)
			(layer "B.SilkS")
		)
		(fp_line
			(start -0.7874 -0.4064)
			(end -0.7874 0.4064)
			(stroke
				(width 0.1524)
				(type default)
			)
			(layer "B.SilkS")
		)
		(fp_line
			(start 0.7874 -0.4064)
			(end -0.7874 -0.4064)
			(stroke
				(width 0.1524)
				(type default)
			)
			(layer "B.SilkS")
		)
		(fp_line
			(start -0.67945 0.3048)
			(end -0.120396 0.3048)
			(stroke
				(width 0.1)
				(type default)
			)
			(layer "B.Fab")
		)
		(fp_line
			(start -0.120396 0.3048)
			(end -0.120396 0.2794)
			(stroke
				(width 0.1)
				(type default)
			)
			(layer "B.Fab")
		)
		(fp_line
			(start 0.12065 0.3048)
			(end 0.67945 0.3048)
			(stroke
				(width 0.1)
				(type default)
			)
			(layer "B.Fab")
		)
		(fp_line
			(start 0.67945 0.3048)
			(end 0.67945 -0.305054)
			(stroke
				(width 0.1)
				(type default)
			)
			(layer "B.Fab")
		)
		(fp_line
			(start -0.120396 0.2794)
			(end 0.12065 0.2794)
			(stroke
				(width 0.1)
				(type default)
			)
			(layer "B.Fab")
		)
		(fp_line
			(start 0.12065 0.2794)
			(end 0.12065 0.3048)
			(stroke
				(width 0.1)
				(type default)
			)
			(layer "B.Fab")
		)
		(fp_line
			(start -0.12065 -0.2794)
			(end -0.12065 -0.3048)
			(stroke
				(width 0.1)
				(type default)
			)
			(layer "B.Fab")
		)
		(fp_line
			(start 0.12065 -0.2794)
			(end -0.12065 -0.2794)
			(stroke
				(width 0.1)
				(type default)
			)
			(layer "B.Fab")
		)
		(fp_line
			(start -0.67945 -0.3048)
			(end -0.67945 0.3048)
			(stroke
				(width 0.1)
				(type default)
			)
			(layer "B.Fab")
		)
		(fp_line
			(start -0.12065 -0.3048)
			(end -0.67945 -0.3048)
			(stroke
				(width 0.1)
				(type default)
			)
			(layer "B.Fab")
		)
		(fp_line
			(start 0.12065 -0.305054)
			(end 0.12065 -0.2794)
			(stroke
				(width 0.1)
				(type default)
			)
			(layer "B.Fab")
		)
		(fp_line
			(start 0.67945 -0.305054)
			(end 0.12065 -0.305054)
			(stroke
				(width 0.1)
				(type default)
			)
			(layer "B.Fab")
		)
		(pad "1" smd circle
			(at 0.40005 0 90)
			(size 0 0)
			(layers "B.Cu" "B.Mask" "B.Paste")
			(net "P0V8_SERDES_VDDA_PEX1")
		)
		(pad "2" smd circle
			(at -0.40005 0 90)
			(size 0 0)
			(layers "B.Cu" "B.Mask" "B.Paste")
			(net "P0V8_SERDES_VDDA_PEX1_C5")
		)
	)
	(footprint ""
		(layer "B.Cu")
		(at 66.299842 -299.699934 -90)
		(property "Reference" "C1175"
			(at 0 0 90)
			(layer "B.SilkS")
			(hide yes)
			(effects
				(font
					(size 1.27 1.27)
				)
				(justify mirror)
			)
		)
		(property "Value" ""
			(at 0 0 90)
			(layer "B.Fab")
			(effects
				(font
					(size 1.27 1.27)
				)
				(justify mirror)
			)
		)
		(duplicate_pad_numbers_are_jumpers no)
		(fp_line
			(start -0.299974 0.150114)
			(end 0.299974 0.150114)
			(stroke
				(width 0.1)
				(type default)
			)
			(layer "B.Fab")
		)
		(fp_line
			(start 0.299974 0.150114)
			(end 0.299974 -0.150114)
			(stroke
				(width 0.1)
				(type default)
			)
			(layer "B.Fab")
		)
		(fp_line
			(start -0.299974 -0.150114)
			(end -0.299974 0.150114)
			(stroke
				(width 0.1)
				(type default)
			)
			(layer "B.Fab")
		)
		(fp_line
			(start 0.299974 -0.150114)
			(end -0.299974 -0.150114)
			(stroke
				(width 0.1)
				(type default)
			)
			(layer "B.Fab")
		)
		(pad "1" smd rect
			(at 0.2667 0 90)
			(size 0.3048 0.381)
			(layers "B.Cu" "B.Mask" "B.Paste")
			(net "P0V8_SERDES_VDDA_PEX0")
		)
		(pad "2" smd rect
			(at -0.2667 0 90)
			(size 0.3048 0.381)
			(layers "B.Cu" "B.Mask" "B.Paste")
			(net "GND")
		)
	)
	(footprint ""
		(layer "B.Cu")
		(at 291.84981 -299.699934 -90)
		(property "Reference" "C1718"
			(at 0 0 90)
			(layer "B.SilkS")
			(hide yes)
			(effects
				(font
					(size 1.27 1.27)
				)
				(justify mirror)
			)
		)
		(property "Value" ""
			(at 0 0 90)
			(layer "B.Fab")
			(effects
				(font
					(size 1.27 1.27)
				)
				(justify mirror)
			)
		)
		(duplicate_pad_numbers_are_jumpers no)
		(fp_line
			(start -0.299974 0.150114)
			(end 0.299974 0.150114)
			(stroke
				(width 0.1)
				(type default)
			)
			(layer "B.Fab")
		)
		(fp_line
			(start 0.299974 0.150114)
			(end 0.299974 -0.150114)
			(stroke
				(width 0.1)
				(type default)
			)
			(layer "B.Fab")
		)
		(fp_line
			(start -0.299974 -0.150114)
			(end -0.299974 0.150114)
			(stroke
				(width 0.1)
				(type default)
			)
			(layer "B.Fab")
		)
		(fp_line
			(start 0.299974 -0.150114)
			(end -0.299974 -0.150114)
			(stroke
				(width 0.1)
				(type default)
			)
			(layer "B.Fab")
		)
		(pad "1" smd rect
			(at 0.2667 0 90)
			(size 0.3048 0.381)
			(layers "B.Cu" "B.Mask" "B.Paste")
			(net "P0V8_SERDES_VDDA_PEX2")
		)
		(pad "2" smd rect
			(at -0.2667 0 90)
			(size 0.3048 0.381)
			(layers "B.Cu" "B.Mask" "B.Paste")
			(net "GND")
		)
	)
	(footprint ""
		(layer "B.Cu")
		(at 183.3499 -292.099746 90)
		(property "Reference" "C1439"
			(at 0 0 90)
			(layer "B.SilkS")
			(hide yes)
			(effects
				(font
					(size 1.27 1.27)
				)
				(justify mirror)
			)
		)
		(property "Value" ""
			(at 0 0 90)
			(layer "B.Fab")
			(effects
				(font
					(size 1.27 1.27)
				)
				(justify mirror)
			)
		)
		(duplicate_pad_numbers_are_jumpers no)
		(fp_line
			(start 0.299974 -0.150114)
			(end -0.299974 -0.150114)
			(stroke
				(width 0.1)
				(type default)
			)
			(layer "B.Fab")
		)
		(fp_line
			(start -0.299974 -0.150114)
			(end -0.299974 0.150114)
			(stroke
				(width 0.1)
				(type default)
			)
			(layer "B.Fab")
		)
		(fp_line
			(start 0.299974 0.150114)
			(end 0.299974 -0.150114)
			(stroke
				(width 0.1)
				(type default)
			)
			(layer "B.Fab")
		)
		(fp_line
			(start -0.299974 0.150114)
			(end 0.299974 0.150114)
			(stroke
				(width 0.1)
				(type default)
			)
			(layer "B.Fab")
		)
		(pad "1" smd rect
			(at 0.2667 0 270)
			(size 0.3048 0.381)
			(layers "B.Cu" "B.Mask" "B.Paste")
			(net "P0V8_SERDES_VDDA_PEX1")
		)
		(pad "2" smd rect
			(at -0.2667 0 270)
			(size 0.3048 0.381)
			(layers "B.Cu" "B.Mask" "B.Paste")
			(net "GND")
		)
	)
	(footprint ""
		(layer "B.Cu")
		(at 375.58853 -238.588296 180)
		(property "Reference" "R911"
			(at 0 0 0)
			(layer "B.SilkS")
			(hide yes)
			(effects
				(font
					(size 1.27 1.27)
				)
				(justify mirror)
			)
		)
		(property "Value" ""
			(at 0 0 0)
			(layer "B.Fab")
			(effects
				(font
					(size 1.27 1.27)
				)
				(justify mirror)
			)
		)
		(duplicate_pad_numbers_are_jumpers no)
		(fp_line
			(start 0.7874 0.4064)
			(end 0.7874 -0.4064)
			(stroke
				(width 0.1524)
				(type default)
			)
			(layer "B.SilkS")
		)
		(fp_line
			(start 0.7874 -0.4064)
			(end -0.7874 -0.4064)
			(stroke
				(width 0.1524)
				(type default)
			)
			(layer "B.SilkS")
		)
		(fp_line
			(start -0.7874 0.4064)
			(end 0.7874 0.4064)
			(stroke
				(width 0.1524)
				(type default)
			)
			(layer "B.SilkS")
		)
		(fp_line
			(start -0.7874 -0.4064)
			(end -0.7874 0.4064)
			(stroke
				(width 0.1524)
				(type default)
			)
			(layer "B.SilkS")
		)
		(fp_line
			(start 0.67945 0.3048)
			(end 0.67945 -0.305054)
			(stroke
				(width 0.1)
				(type default)
			)
			(layer "B.Fab")
		)
		(fp_line
			(start 0.67945 -0.305054)
			(end 0.12065 -0.305054)
			(stroke
				(width 0.1)
				(type default)
			)
			(layer "B.Fab")
		)
		(fp_line
			(start 0.12065 0.3048)
			(end 0.67945 0.3048)
			(stroke
				(width 0.1)
				(type default)
			)
			(layer "B.Fab")
		)
		(fp_line
			(start 0.12065 0.2794)
			(end 0.12065 0.3048)
			(stroke
				(width 0.1)
				(type default)
			)
			(layer "B.Fab")
		)
		(fp_line
			(start 0.12065 -0.2794)
			(end -0.12065 -0.2794)
			(stroke
				(width 0.1)
				(type default)
			)
			(layer "B.Fab")
		)
		(fp_line
			(start 0.12065 -0.305054)
			(end 0.12065 -0.2794)
			(stroke
				(width 0.1)
				(type default)
			)
			(layer "B.Fab")
		)
		(fp_line
			(start -0.120396 0.3048)
			(end -0.120396 0.2794)
			(stroke
				(width 0.1)
				(type default)
			)
			(layer "B.Fab")
		)
		(fp_line
			(start -0.120396 0.2794)
			(end 0.12065 0.2794)
			(stroke
				(width 0.1)
				(type default)
			)
			(layer "B.Fab")
		)
		(fp_line
			(start -0.12065 -0.2794)
			(end -0.12065 -0.3048)
			(stroke
				(width 0.1)
				(type default)
			)
			(layer "B.Fab")
		)
		(fp_line
			(start -0.12065 -0.3048)
			(end -0.67945 -0.3048)
			(stroke
				(width 0.1)
				(type default)
			)
			(layer "B.Fab")
		)
		(fp_line
			(start -0.67945 0.3048)
			(end -0.120396 0.3048)
			(stroke
				(width 0.1)
				(type default)
			)
			(layer "B.Fab")
		)
		(fp_line
			(start -0.67945 -0.3048)
			(end -0.67945 0.3048)
			(stroke
				(width 0.1)
				(type default)
			)
			(layer "B.Fab")
		)
		(pad "1" smd circle
			(at 0.40005 0)
			(size 0 0)
			(layers "B.Cu" "B.Mask" "B.Paste")
			(net "FT4232_SDB_EEPROM_R_SCL")
		)
		(pad "2" smd circle
			(at -0.40005 0)
			(size 0 0)
			(layers "B.Cu" "B.Mask" "B.Paste")
			(net "P3V3_AUX")
		)
	)
	(footprint ""
		(layer "B.Cu")
		(at 113.346484 -321.371468 -90)
		(property "Reference" "R6456"
			(at 0 0 90)
			(layer "B.SilkS")
			(hide yes)
			(effects
				(font
					(size 1.27 1.27)
				)
				(justify mirror)
			)
		)
		(property "Value" ""
			(at 0 0 90)
			(layer "B.Fab")
			(effects
				(font
					(size 1.27 1.27)
				)
				(justify mirror)
			)
		)
		(duplicate_pad_numbers_are_jumpers no)
		(fp_line
			(start -0.7874 0.4064)
			(end 0.7874 0.4064)
			(stroke
				(width 0.1524)
				(type default)
			)
			(layer "B.SilkS")
		)
		(fp_line
			(start 0.7874 0.4064)
			(end 0.7874 -0.4064)
			(stroke
				(width 0.1524)
				(type default)
			)
			(layer "B.SilkS")
		)
		(fp_line
			(start -0.7874 -0.4064)
			(end -0.7874 0.4064)
			(stroke
				(width 0.1524)
				(type default)
			)
			(layer "B.SilkS")
		)
		(fp_line
			(start 0.7874 -0.4064)
			(end -0.7874 -0.4064)
			(stroke
				(width 0.1524)
				(type default)
			)
			(layer "B.SilkS")
		)
		(fp_line
			(start -0.67945 0.3048)
			(end -0.120396 0.3048)
			(stroke
				(width 0.1)
				(type default)
			)
			(layer "B.Fab")
		)
		(fp_line
			(start -0.120396 0.3048)
			(end -0.120396 0.2794)
			(stroke
				(width 0.1)
				(type default)
			)
			(layer "B.Fab")
		)
		(fp_line
			(start 0.12065 0.3048)
			(end 0.67945 0.3048)
			(stroke
				(width 0.1)
				(type default)
			)
			(layer "B.Fab")
		)
		(fp_line
			(start 0.67945 0.3048)
			(end 0.67945 -0.305054)
			(stroke
				(width 0.1)
				(type default)
			)
			(layer "B.Fab")
		)
		(fp_line
			(start -0.120396 0.2794)
			(end 0.12065 0.2794)
			(stroke
				(width 0.1)
				(type default)
			)
			(layer "B.Fab")
		)
		(fp_line
			(start 0.12065 0.2794)
			(end 0.12065 0.3048)
			(stroke
				(width 0.1)
				(type default)
			)
			(layer "B.Fab")
		)
		(fp_line
			(start -0.12065 -0.2794)
			(end -0.12065 -0.3048)
			(stroke
				(width 0.1)
				(type default)
			)
			(layer "B.Fab")
		)
		(fp_line
			(start 0.12065 -0.2794)
			(end -0.12065 -0.2794)
			(stroke
				(width 0.1)
				(type default)
			)
			(layer "B.Fab")
		)
		(fp_line
			(start -0.67945 -0.3048)
			(end -0.67945 0.3048)
			(stroke
				(width 0.1)
				(type default)
			)
			(layer "B.Fab")
		)
		(fp_line
			(start -0.12065 -0.3048)
			(end -0.67945 -0.3048)
			(stroke
				(width 0.1)
				(type default)
			)
			(layer "B.Fab")
		)
		(fp_line
			(start 0.12065 -0.305054)
			(end 0.12065 -0.2794)
			(stroke
				(width 0.1)
				(type default)
			)
			(layer "B.Fab")
		)
		(fp_line
			(start 0.67945 -0.305054)
			(end 0.12065 -0.305054)
			(stroke
				(width 0.1)
				(type default)
			)
			(layer "B.Fab")
		)
		(pad "1" smd circle
			(at 0.40005 0 90)
			(size 0 0)
			(layers "B.Cu" "B.Mask" "B.Paste")
			(net "P0V8_SERDES_VDDA_PEX0")
		)
		(pad "2" smd circle
			(at -0.40005 0 90)
			(size 0 0)
			(layers "B.Cu" "B.Mask" "B.Paste")
			(net "P0V8_SERDES_VDDA_PEX0_C7")
		)
	)
	(footprint ""
		(layer "B.Cu")
		(at 404.625048 -297.79976 -90)
		(property "Reference" "C1884"
			(at 0 0 90)
			(layer "B.SilkS")
			(hide yes)
			(effects
				(font
					(size 1.27 1.27)
				)
				(justify mirror)
			)
		)
		(property "Value" ""
			(at 0 0 90)
			(layer "B.Fab")
			(effects
				(font
					(size 1.27 1.27)
				)
				(justify mirror)
			)
		)
		(duplicate_pad_numbers_are_jumpers no)
		(fp_line
			(start -0.299974 0.150114)
			(end 0.299974 0.150114)
			(stroke
				(width 0.1)
				(type default)
			)
			(layer "B.Fab")
		)
		(fp_line
			(start 0.299974 0.150114)
			(end 0.299974 -0.150114)
			(stroke
				(width 0.1)
				(type default)
			)
			(layer "B.Fab")
		)
		(fp_line
			(start -0.299974 -0.150114)
			(end -0.299974 0.150114)
			(stroke
				(width 0.1)
				(type default)
			)
			(layer "B.Fab")
		)
		(fp_line
			(start 0.299974 -0.150114)
			(end -0.299974 -0.150114)
			(stroke
				(width 0.1)
				(type default)
			)
			(layer "B.Fab")
		)
		(pad "1" smd rect
			(at 0.2667 0 90)
			(size 0.3048 0.381)
			(layers "B.Cu" "B.Mask" "B.Paste")
			(net "P0V8_PEX3")
		)
		(pad "2" smd rect
			(at -0.2667 0 90)
			(size 0.3048 0.381)
			(layers "B.Cu" "B.Mask" "B.Paste")
			(net "GND")
		)
	)
	(footprint ""
		(layer "B.Cu")
		(at 302.303942 -98.552)
		(property "Reference" "R278"
			(at 0 0 0)
			(layer "B.SilkS")
			(hide yes)
			(effects
				(font
					(size 1.27 1.27)
				)
				(justify mirror)
			)
		)
		(property "Value" ""
			(at 0 0 0)
			(layer "B.Fab")
			(effects
				(font
					(size 1.27 1.27)
				)
				(justify mirror)
			)
		)
		(duplicate_pad_numbers_are_jumpers no)
		(fp_line
			(start -0.7874 -0.4064)
			(end -0.7874 0.4064)
			(stroke
				(width 0.1524)
				(type default)
			)
			(layer "B.SilkS")
		)
		(fp_line
			(start -0.7874 0.4064)
			(end 0.7874 0.4064)
			(stroke
				(width 0.1524)
				(type default)
			)
			(layer "B.SilkS")
		)
		(fp_line
			(start 0.7874 -0.4064)
			(end -0.7874 -0.4064)
			(stroke
				(width 0.1524)
				(type default)
			)
			(layer "B.SilkS")
		)
		(fp_line
			(start 0.7874 0.4064)
			(end 0.7874 -0.4064)
			(stroke
				(width 0.1524)
				(type default)
			)
			(layer "B.SilkS")
		)
		(fp_line
			(start -0.67945 -0.3048)
			(end -0.67945 0.3048)
			(stroke
				(width 0.1)
				(type default)
			)
			(layer "B.Fab")
		)
		(fp_line
			(start -0.67945 0.3048)
			(end -0.120396 0.3048)
			(stroke
				(width 0.1)
				(type default)
			)
			(layer "B.Fab")
		)
		(fp_line
			(start -0.12065 -0.3048)
			(end -0.67945 -0.3048)
			(stroke
				(width 0.1)
				(type default)
			)
			(layer "B.Fab")
		)
		(fp_line
			(start -0.12065 -0.2794)
			(end -0.12065 -0.3048)
			(stroke
				(width 0.1)
				(type default)
			)
			(layer "B.Fab")
		)
		(fp_line
			(start -0.120396 0.2794)
			(end 0.12065 0.2794)
			(stroke
				(width 0.1)
				(type default)
			)
			(layer "B.Fab")
		)
		(fp_line
			(start -0.120396 0.3048)
			(end -0.120396 0.2794)
			(stroke
				(width 0.1)
				(type default)
			)
			(layer "B.Fab")
		)
		(fp_line
			(start 0.12065 -0.305054)
			(end 0.12065 -0.2794)
			(stroke
				(width 0.1)
				(type default)
			)
			(layer "B.Fab")
		)
		(fp_line
			(start 0.12065 -0.2794)
			(end -0.12065 -0.2794)
			(stroke
				(width 0.1)
				(type default)
			)
			(layer "B.Fab")
		)
		(fp_line
			(start 0.12065 0.2794)
			(end 0.12065 0.3048)
			(stroke
				(width 0.1)
				(type default)
			)
			(layer "B.Fab")
		)
		(fp_line
			(start 0.12065 0.3048)
			(end 0.67945 0.3048)
			(stroke
				(width 0.1)
				(type default)
			)
			(layer "B.Fab")
		)
		(fp_line
			(start 0.67945 -0.305054)
			(end 0.12065 -0.305054)
			(stroke
				(width 0.1)
				(type default)
			)
			(layer "B.Fab")
		)
		(fp_line
			(start 0.67945 0.3048)
			(end 0.67945 -0.305054)
			(stroke
				(width 0.1)
				(type default)
			)
			(layer "B.Fab")
		)
		(pad "1" smd circle
			(at 0.40005 0 180)
			(size 0 0)
			(layers "B.Cu" "B.Mask" "B.Paste")
			(net "NIC5_MAIN_PWR_EN")
		)
		(pad "2" smd circle
			(at -0.40005 0 180)
			(size 0 0)
			(layers "B.Cu" "B.Mask" "B.Paste")
			(net "GND")
		)
	)
)
